# T6G (Grand Teton) — schematic netlist excerpt (pin names and nets, part order shuffled) for the footprints in the layout excerpt that follows; sources: Cadence DE-HDL packaged netlist, KiCad conversion of 04192023_DAF0TMB3IC0_F0TG_MB_C_brd_V02_OCP.brd

PR6530  Q_RES  49.9 1% CHIP  pkg 0402LF  page 362 : A = P0V9_RETIMER_CPU0_SENSE_SH_P ; B = P0V9_CPU0_RT_2D
PC569_5  Q_CAP  1UF 25V 10% X6S  pkg C0402  page 196 : A = SW_P12V_AUX_PVDDCR_CPU0_P0_FLT ; B = GND

(kicad_pcb
	(version 20260206)
	(generator "pcbnew")
	(generator_version "10.0")
	(general
		(thickness 1.6)
		(legacy_teardrops no)
	)
	(paper "A4")
	(title_block
		(title "04192023_DAF0TMB3IC0_F0TG_MB_C_brd_V02_OCP.brd")
		(comment 1 "Grand Teton / footprints 1576-1577 of 8354")
	)
	(layers
		(0 "F.Cu" signal "TOP")
		(4 "In1.Cu" signal "GND")
		(6 "In2.Cu" signal "IN1")
		(8 "In3.Cu" signal "GND1")
		(10 "In4.Cu" signal "IN2")
		(12 "In5.Cu" signal "GND2")
		(14 "In6.Cu" signal "IN3")
		(16 "In7.Cu" signal "GND3")
		(18 "In8.Cu" signal "VCC")
		(20 "In9.Cu" signal "VCC1")
		(22 "In10.Cu" signal "GND4")
		(24 "In11.Cu" signal "IN4")
		(26 "In12.Cu" signal "GND5")
		(28 "In13.Cu" signal "IN5")
		(30 "In14.Cu" signal "GND6")
		(32 "In15.Cu" signal "IN6")
		(34 "In16.Cu" signal "GND7")
		(2 "B.Cu" signal "BOTTOM")
		(9 "F.Adhes" user "F.Adhesive")
		(11 "B.Adhes" user "B.Adhesive")
		(13 "F.Paste" user "Package Geometry/Pastemask Top")
		(15 "B.Paste" user "Package Geometry/Pastemask Bottom")
		(5 "F.SilkS" user "Ref Des/Silkscreen Top")
		(7 "B.SilkS" user "Ref Des/Silkscreen Bottom")
		(1 "F.Mask" user "Board Geometry/Soldermask Top")
		(3 "B.Mask" user "Board Geometry/Soldermask Bottom")
		(17 "Dwgs.User" user "User.Drawings")
		(19 "Cmts.User" user "User.Comments")
		(21 "Eco1.User" user "User.Eco1")
		(23 "Eco2.User" user "User.Eco2")
		(25 "Edge.Cuts" user "Board Geometry/Outline")
		(27 "Margin" user)
		(31 "F.CrtYd" user "Package Geometry/Place Bound Top")
		(29 "B.CrtYd" user "Package Geometry/Place Bound Bottom")
		(35 "F.Fab" user "Ref Des/Assembly Top")
		(33 "B.Fab" user "Ref Des/Assembly Bottom")
	)
	(footprint ""
		(layer "F.Cu")
		(at 352.373438 -169.413174 90)
		(property "Reference" "PC569_5"
			(at 0 0 90)
			(layer "F.SilkS")
			(hide yes)
			(effects
				(font
					(size 1.27 1.27)
				)
			)
		)
		(property "Value" ""
			(at 0 0 90)
			(layer "F.Fab")
			(effects
				(font
					(size 1.27 1.27)
				)
			)
		)
		(duplicate_pad_numbers_are_jumpers no)
		(fp_line
			(start 0.7874 -0.4064)
			(end 0.7874 0.4064)
			(stroke
				(width 0.1524)
				(type default)
			)
			(layer "F.SilkS")
		)
		(fp_line
			(start -0.7874 -0.4064)
			(end 0.7874 -0.4064)
			(stroke
				(width 0.1524)
				(type default)
			)
			(layer "F.SilkS")
		)
		(fp_line
			(start 0.7874 0.4064)
			(end -0.7874 0.4064)
			(stroke
				(width 0.1524)
				(type default)
			)
			(layer "F.SilkS")
		)
		(fp_line
			(start -0.7874 0.4064)
			(end -0.7874 -0.4064)
			(stroke
				(width 0.1524)
				(type default)
			)
			(layer "F.SilkS")
		)
		(fp_line
			(start -0.12065 -0.305054)
			(end -0.12065 -0.2794)
			(stroke
				(width 0.1)
				(type default)
			)
			(layer "F.Fab")
		)
		(fp_line
			(start -0.67945 -0.305054)
			(end -0.12065 -0.305054)
			(stroke
				(width 0.1)
				(type default)
			)
			(layer "F.Fab")
		)
		(fp_line
			(start 0.67945 -0.3048)
			(end 0.67945 0.3048)
			(stroke
				(width 0.1)
				(type default)
			)
			(layer "F.Fab")
		)
		(fp_line
			(start 0.12065 -0.3048)
			(end 0.67945 -0.3048)
			(stroke
				(width 0.1)
				(type default)
			)
			(layer "F.Fab")
		)
		(fp_line
			(start 0.12065 -0.2794)
			(end 0.12065 -0.3048)
			(stroke
				(width 0.1)
				(type default)
			)
			(layer "F.Fab")
		)
		(fp_line
			(start -0.12065 -0.2794)
			(end 0.12065 -0.2794)
			(stroke
				(width 0.1)
				(type default)
			)
			(layer "F.Fab")
		)
		(fp_line
			(start 0.120396 0.2794)
			(end -0.12065 0.2794)
			(stroke
				(width 0.1)
				(type default)
			)
			(layer "F.Fab")
		)
		(fp_line
			(start -0.12065 0.2794)
			(end -0.12065 0.3048)
			(stroke
				(width 0.1)
				(type default)
			)
			(layer "F.Fab")
		)
		(fp_line
			(start 0.67945 0.3048)
			(end 0.120396 0.3048)
			(stroke
				(width 0.1)
				(type default)
			)
			(layer "F.Fab")
		)
		(fp_line
			(start 0.120396 0.3048)
			(end 0.120396 0.2794)
			(stroke
				(width 0.1)
				(type default)
			)
			(layer "F.Fab")
		)
		(fp_line
			(start -0.12065 0.3048)
			(end -0.67945 0.3048)
			(stroke
				(width 0.1)
				(type default)
			)
			(layer "F.Fab")
		)
		(fp_line
			(start -0.67945 0.3048)
			(end -0.67945 -0.305054)
			(stroke
				(width 0.1)
				(type default)
			)
			(layer "F.Fab")
		)
		(pad "1" smd circle
			(at -0.40005 0 90)
			(size 0 0)
			(layers "F.Cu" "F.Mask" "F.Paste")
			(net "SW_P12V_AUX_PVDDCR_CPU0_P0_FLT")
		)
		(pad "2" smd circle
			(at 0.40005 0 90)
			(size 0 0)
			(layers "F.Cu" "F.Mask" "F.Paste")
			(net "GND")
		)
	)
	(footprint ""
		(layer "F.Cu")
		(at 439.821066 -388.8613)
		(property "Reference" "PR6530"
			(at 0 0 0)
			(layer "F.SilkS")
			(hide yes)
			(effects
				(font
					(size 1.27 1.27)
				)
			)
		)
		(property "Value" ""
			(at 0 0 0)
			(layer "F.Fab")
			(effects
				(font
					(size 1.27 1.27)
				)
			)
		)
		(duplicate_pad_numbers_are_jumpers no)
		(fp_line
			(start -0.7874 -0.4064)
			(end 0.7874 -0.4064)
			(stroke
				(width 0.1524)
				(type default)
			)
			(layer "F.SilkS")
		)
		(fp_line
			(start -0.7874 0.4064)
			(end -0.7874 -0.4064)
			(stroke
				(width 0.1524)
				(type default)
			)
			(layer "F.SilkS")
		)
		(fp_line
			(start 0.7874 -0.4064)
			(end 0.7874 0.4064)
			(stroke
				(width 0.1524)
				(type default)
			)
			(layer "F.SilkS")
		)
		(fp_line
			(start 0.7874 0.4064)
			(end -0.7874 0.4064)
			(stroke
				(width 0.1524)
				(type default)
			)
			(layer "F.SilkS")
		)
		(fp_line
			(start -0.67945 -0.305054)
			(end -0.12065 -0.305054)
			(stroke
				(width 0.1)
				(type default)
			)
			(layer "F.Fab")
		)
		(fp_line
			(start -0.67945 0.3048)
			(end -0.67945 -0.305054)
			(stroke
				(width 0.1)
				(type default)
			)
			(layer "F.Fab")
		)
		(fp_line
			(start -0.12065 -0.305054)
			(end -0.12065 -0.2794)
			(stroke
				(width 0.1)
				(type default)
			)
			(layer "F.Fab")
		)
		(fp_line
			(start -0.12065 -0.2794)
			(end 0.12065 -0.2794)
			(stroke
				(width 0.1)
				(type default)
			)
			(layer "F.Fab")
		)
		(fp_line
			(start -0.12065 0.2794)
			(end -0.12065 0.3048)
			(stroke
				(width 0.1)
				(type default)
			)
			(layer "F.Fab")
		)
		(fp_line
			(start -0.12065 0.3048)
			(end -0.67945 0.3048)
			(stroke
				(width 0.1)
				(type default)
			)
			(layer "F.Fab")
		)
		(fp_line
			(start 0.120396 0.2794)
			(end -0.12065 0.2794)
			(stroke
				(width 0.1)
				(type default)
			)
			(layer "F.Fab")
		)
		(fp_line
			(start 0.120396 0.3048)
			(end 0.120396 0.2794)
			(stroke
				(width 0.1)
				(type default)
			)
			(layer "F.Fab")
		)
		(fp_line
			(start 0.12065 -0.3048)
			(end 0.67945 -0.3048)
			(stroke
				(width 0.1)
				(type default)
			)
			(layer "F.Fab")
		)
		(fp_line
			(start 0.12065 -0.2794)
			(end 0.12065 -0.3048)
			(stroke
				(width 0.1)
				(type default)
			)
			(layer "F.Fab")
		)
		(fp_line
			(start 0.67945 -0.3048)
			(end 0.67945 0.3048)
			(stroke
				(width 0.1)
				(type default)
			)
			(layer "F.Fab")
		)
		(fp_line
			(start 0.67945 0.3048)
			(end 0.120396 0.3048)
			(stroke
				(width 0.1)
				(type default)
			)
			(layer "F.Fab")
		)
		(pad "1" smd circle
			(at -0.40005 0)
			(size 0 0)
			(layers "F.Cu" "F.Mask" "F.Paste")
			(net "P0V9_RETIMER_CPU0_SENSE_SH_P")
		)
		(pad "2" smd circle
			(at 0.40005 0)
			(size 0 0)
			(layers "F.Cu" "F.Mask" "F.Paste")
			(net "P0V9_CPU0_RT_2D")
		)
	)
)
